# T6G (Grand Teton) — schematic netlist excerpt (pin names and nets, part order shuffled) for the footprints in the layout excerpt that follows; sources: Cadence DE-HDL packaged netlist, KiCad conversion of 04192023_DAF0TMB3IC0_F0TG_MB_C_brd_V02_OCP.brd

C1555  Q_CAP_DIFFBUS  DIFF BUS_0.22UF 6.3V 20% X6S  pkg C0201  page 65 : \1\ = P5E_CPU0_G3_TX_C_DP<12> ; \2\ = P5E_CPU0_G3_TX_DP<12>
R1336  Q_RES  0 5% EMPTY  pkg 0402LF  page 159 : A = I3C_SPD_DDRGL_CPU1_BYPASS_SCL ; B = I3C_SPD_DDRGL_CPU1_SCL
R1387  Q_RES  4.7K 5% CHIP  pkg 0201LF  page 320 : A = CLKREQ_RT_CPU1_P0_N ; B = GND

(kicad_pcb
	(version 20260206)
	(generator "pcbnew")
	(generator_version "10.0")
	(general
		(thickness 1.6)
		(legacy_teardrops no)
	)
	(paper "A4")
	(title_block
		(title "04192023_DAF0TMB3IC0_F0TG_MB_C_brd_V02_OCP.brd")
		(comment 1 "Grand Teton / footprints 733-735 of 8354")
	)
	(layers
		(0 "F.Cu" signal "TOP")
		(4 "In1.Cu" signal "GND")
		(6 "In2.Cu" signal "IN1")
		(8 "In3.Cu" signal "GND1")
		(10 "In4.Cu" signal "IN2")
		(12 "In5.Cu" signal "GND2")
		(14 "In6.Cu" signal "IN3")
		(16 "In7.Cu" signal "GND3")
		(18 "In8.Cu" signal "VCC")
		(20 "In9.Cu" signal "VCC1")
		(22 "In10.Cu" signal "GND4")
		(24 "In11.Cu" signal "IN4")
		(26 "In12.Cu" signal "GND5")
		(28 "In13.Cu" signal "IN5")
		(30 "In14.Cu" signal "GND6")
		(32 "In15.Cu" signal "IN6")
		(34 "In16.Cu" signal "GND7")
		(2 "B.Cu" signal "BOTTOM")
		(9 "F.Adhes" user "F.Adhesive")
		(11 "B.Adhes" user "B.Adhesive")
		(13 "F.Paste" user "Package Geometry/Pastemask Top")
		(15 "B.Paste" user "Package Geometry/Pastemask Bottom")
		(5 "F.SilkS" user "Ref Des/Silkscreen Top")
		(7 "B.SilkS" user "Ref Des/Silkscreen Bottom")
		(1 "F.Mask" user "Board Geometry/Soldermask Top")
		(3 "B.Mask" user "Board Geometry/Soldermask Bottom")
		(17 "Dwgs.User" user "User.Drawings")
		(19 "Cmts.User" user "User.Comments")
		(21 "Eco1.User" user "User.Eco1")
		(23 "Eco2.User" user "User.Eco2")
		(25 "Edge.Cuts" user "Board Geometry/Outline")
		(27 "Margin" user)
		(31 "F.CrtYd" user "Package Geometry/Place Bound Top")
		(29 "B.CrtYd" user "Package Geometry/Place Bound Bottom")
		(35 "F.Fab" user "Ref Des/Assembly Top")
		(33 "B.Fab" user "Ref Des/Assembly Bottom")
	)
	(footprint ""
		(layer "F.Cu")
		(at 181.388766 -169.117518 -90)
		(property "Reference" "R1336"
			(at 0 0 270)
			(layer "F.SilkS")
			(hide yes)
			(effects
				(font
					(size 1.27 1.27)
				)
			)
		)
		(property "Value" ""
			(at 0 0 270)
			(layer "F.Fab")
			(effects
				(font
					(size 1.27 1.27)
				)
			)
		)
		(duplicate_pad_numbers_are_jumpers no)
		(fp_line
			(start -0.7874 0.4064)
			(end -0.7874 -0.4064)
			(stroke
				(width 0.1524)
				(type default)
			)
			(layer "F.SilkS")
		)
		(fp_line
			(start 0.7874 0.4064)
			(end -0.7874 0.4064)
			(stroke
				(width 0.1524)
				(type default)
			)
			(layer "F.SilkS")
		)
		(fp_line
			(start -0.7874 -0.4064)
			(end 0.7874 -0.4064)
			(stroke
				(width 0.1524)
				(type default)
			)
			(layer "F.SilkS")
		)
		(fp_line
			(start 0.7874 -0.4064)
			(end 0.7874 0.4064)
			(stroke
				(width 0.1524)
				(type default)
			)
			(layer "F.SilkS")
		)
		(fp_line
			(start -0.67945 0.3048)
			(end -0.67945 -0.305054)
			(stroke
				(width 0.1)
				(type default)
			)
			(layer "F.Fab")
		)
		(fp_line
			(start -0.12065 0.3048)
			(end -0.67945 0.3048)
			(stroke
				(width 0.1)
				(type default)
			)
			(layer "F.Fab")
		)
		(fp_line
			(start 0.120396 0.3048)
			(end 0.120396 0.2794)
			(stroke
				(width 0.1)
				(type default)
			)
			(layer "F.Fab")
		)
		(fp_line
			(start 0.67945 0.3048)
			(end 0.120396 0.3048)
			(stroke
				(width 0.1)
				(type default)
			)
			(layer "F.Fab")
		)
		(fp_line
			(start -0.12065 0.2794)
			(end -0.12065 0.3048)
			(stroke
				(width 0.1)
				(type default)
			)
			(layer "F.Fab")
		)
		(fp_line
			(start 0.120396 0.2794)
			(end -0.12065 0.2794)
			(stroke
				(width 0.1)
				(type default)
			)
			(layer "F.Fab")
		)
		(fp_line
			(start -0.12065 -0.2794)
			(end 0.12065 -0.2794)
			(stroke
				(width 0.1)
				(type default)
			)
			(layer "F.Fab")
		)
		(fp_line
			(start 0.12065 -0.2794)
			(end 0.12065 -0.3048)
			(stroke
				(width 0.1)
				(type default)
			)
			(layer "F.Fab")
		)
		(fp_line
			(start 0.12065 -0.3048)
			(end 0.67945 -0.3048)
			(stroke
				(width 0.1)
				(type default)
			)
			(layer "F.Fab")
		)
		(fp_line
			(start 0.67945 -0.3048)
			(end 0.67945 0.3048)
			(stroke
				(width 0.1)
				(type default)
			)
			(layer "F.Fab")
		)
		(fp_line
			(start -0.67945 -0.305054)
			(end -0.12065 -0.305054)
			(stroke
				(width 0.1)
				(type default)
			)
			(layer "F.Fab")
		)
		(fp_line
			(start -0.12065 -0.305054)
			(end -0.12065 -0.2794)
			(stroke
				(width 0.1)
				(type default)
			)
			(layer "F.Fab")
		)
		(pad "1" smd rect
			(at -0.40005 0 90)
			(size 0.4572 0.508)
			(layers "F.Cu" "F.Mask" "F.Paste")
			(net "I3C_SPD_DDRGL_CPU1_BYPASS_SCL")
		)
		(pad "2" smd rect
			(at 0.40005 0 90)
			(size 0.4572 0.508)
			(layers "F.Cu" "F.Mask" "F.Paste")
			(net "I3C_SPD_DDRGL_CPU1_SCL")
		)
	)
	(footprint ""
		(layer "F.Cu")
		(at 70.9676 -381.7874)
		(property "Reference" "R1387"
			(at 0 0 0)
			(layer "F.SilkS")
			(hide yes)
			(effects
				(font
					(size 1.27 1.27)
				)
			)
		)
		(property "Value" ""
			(at 0 0 0)
			(layer "F.Fab")
			(effects
				(font
					(size 1.27 1.27)
				)
			)
		)
		(duplicate_pad_numbers_are_jumpers no)
		(fp_line
			(start -0.32512 -0.175006)
			(end 0.32512 -0.175006)
			(stroke
				(width 0.1)
				(type default)
			)
			(layer "F.Fab")
		)
		(fp_line
			(start -0.32512 0.175006)
			(end -0.32512 -0.175006)
			(stroke
				(width 0.1)
				(type default)
			)
			(layer "F.Fab")
		)
		(fp_line
			(start 0.32512 -0.175006)
			(end 0.32512 0.175006)
			(stroke
				(width 0.1)
				(type default)
			)
			(layer "F.Fab")
		)
		(fp_line
			(start 0.32512 0.175006)
			(end -0.32512 0.175006)
			(stroke
				(width 0.1)
				(type default)
			)
			(layer "F.Fab")
		)
		(pad "1" smd rect
			(at -0.2667 0)
			(size 0.3048 0.381)
			(layers "F.Cu" "F.Mask" "F.Paste")
			(net "CLKREQ_RT_CPU1_P0_N")
		)
		(pad "2" smd rect
			(at 0.2667 0 180)
			(size 0.3048 0.381)
			(layers "F.Cu" "F.Mask" "F.Paste")
			(net "GND")
		)
	)
	(footprint ""
		(layer "F.Cu")
		(at 399.303748 -17.624298 90)
		(property "Reference" "C1555"
			(at 0 0 90)
			(layer "F.SilkS")
			(hide yes)
			(effects
				(font
					(size 1.27 1.27)
				)
			)
		)
		(property "Value" ""
			(at 0 0 90)
			(layer "F.Fab")
			(effects
				(font
					(size 1.27 1.27)
				)
			)
		)
		(duplicate_pad_numbers_are_jumpers no)
		(fp_line
			(start 0.299974 -0.150114)
			(end 0.299974 0.150114)
			(stroke
				(width 0.1)
				(type default)
			)
			(layer "F.Fab")
		)
		(fp_line
			(start -0.299974 -0.150114)
			(end 0.299974 -0.150114)
			(stroke
				(width 0.1)
				(type default)
			)
			(layer "F.Fab")
		)
		(fp_line
			(start 0.299974 0.150114)
			(end -0.299974 0.150114)
			(stroke
				(width 0.1)
				(type default)
			)
			(layer "F.Fab")
		)
		(fp_line
			(start -0.299974 0.150114)
			(end -0.299974 -0.150114)
			(stroke
				(width 0.1)
				(type default)
			)
			(layer "F.Fab")
		)
		(pad "1" smd rect
			(at -0.2667 0 90)
			(size 0.3048 0.381)
			(layers "F.Cu" "F.Mask" "F.Paste")
			(net "P5E_CPU0_G3_TX_C_DP<12>")
		)
		(pad "2" smd rect
			(at 0.2667 0 90)
			(size 0.3048 0.381)
			(layers "F.Cu" "F.Mask" "F.Paste")
			(net "P5E_CPU0_G3_TX_DP<12>")
		)
	)
)
